(kicad_pcb
	(version 20241229)
	(generator "pcbnew")
	(generator_version "9.0")
	(general
		(thickness 1.61)
		(legacy_teardrops no)
	)
	(paper "A3")
	(title_block
		(title "RDIMM DDR5 Tester")
		(date "2026-05-21")
		(rev "2.2.0")
		(company "Antmicro")
		(comment 9 "footprints 133-137 of 796")
	)
	(layers
		(0 "F.Cu" signal)
		(4 "In1.Cu" power)
		(6 "In2.Cu" mixed)
		(8 "In3.Cu" power)
		(10 "In4.Cu" mixed)
		(12 "In5.Cu" power)
		(14 "In6.Cu" mixed)
		(16 "In7.Cu" power)
		(18 "In8.Cu" power)
		(20 "In9.Cu" mixed)
		(22 "In10.Cu" power)
		(2 "B.Cu" signal)
		(9 "F.Adhes" user "F.Adhesive")
		(11 "B.Adhes" user "B.Adhesive")
		(13 "F.Paste" user)
		(15 "B.Paste" user)
		(5 "F.SilkS" user "F.Silkscreen")
		(7 "B.SilkS" user "B.Silkscreen")
		(1 "F.Mask" user)
		(3 "B.Mask" user)
		(17 "Dwgs.User" user "User.Drawings")
		(19 "Cmts.User" user "User.Comments")
		(21 "Eco1.User" user "User.Eco1")
		(23 "Eco2.User" user "User.Eco2")
		(25 "Edge.Cuts" user)
		(27 "Margin" user)
		(31 "F.CrtYd" user "F.Courtyard")
		(29 "B.CrtYd" user "B.Courtyard")
		(35 "F.Fab" user)
		(33 "B.Fab" user)
	)
	(footprint "antmicro-footprints:C_0402_1005Metric"
		(layer "F.Cu")
		(at 223.15 178.85 90)
		(descr "Capacitor SMD 0402")
		(tags "capacitor SMD 0402")
		(property "Reference" "C215"
			(at -5.67 0.99 90)
			(layer "F.SilkS")
			(effects
				(font
					(size 0.7 0.7)
					(thickness 0.15)
				)
				(justify left bottom)
			)
		)
		(property "Value" "C_220n_16V_0402"
			(at -1.022927 2.155213 90)
			(layer "F.Fab")
			(effects
				(font
					(size 0.7 0.7)
					(thickness 0.15)
				)
				(justify left bottom)
			)
		)
		(property "Datasheet" "https://www.murata.com/products/productdetail?partno=GRM155R71C224KA12%23"
			(at 0 0 90)
			(layer "F.Fab")
			(hide yes)
			(effects
				(font
					(size 1.27 1.27)
					(thickness 0.15)
				)
			)
		)
		(property "MPN" "GRM155R71C224KA12D"
			(at 0 0 90)
			(unlocked yes)
			(layer "F.Fab")
			(hide yes)
			(effects
				(font
					(size 1 1)
					(thickness 0.15)
				)
			)
		)
		(property "Manufacturer" "Murata"
			(at 0 0 90)
			(unlocked yes)
			(layer "F.Fab")
			(hide yes)
			(effects
				(font
					(size 1 1)
					(thickness 0.15)
				)
			)
		)
		(property "License" "Apache-2.0"
			(at 0 0 90)
			(unlocked yes)
			(layer "F.Fab")
			(hide yes)
			(effects
				(font
					(size 1 1)
					(thickness 0.15)
				)
			)
		)
		(property "Author" "Antmicro"
			(at 0 0 90)
			(unlocked yes)
			(layer "F.Fab")
			(hide yes)
			(effects
				(font
					(size 1 1)
					(thickness 0.15)
				)
			)
		)
		(property "Val" "220n"
			(at 0 0 90)
			(unlocked yes)
			(layer "F.Fab")
			(hide yes)
			(effects
				(font
					(size 1 1)
					(thickness 0.15)
				)
			)
		)
		(property "Voltage" "16V"
			(at 0 0 90)
			(unlocked yes)
			(layer "F.Fab")
			(hide yes)
			(effects
				(font
					(size 1 1)
					(thickness 0.15)
				)
			)
		)
		(property "Dielectric" "X7R"
			(at 0 0 90)
			(unlocked yes)
			(layer "F.Fab")
			(hide yes)
			(effects
				(font
					(size 1 1)
					(thickness 0.15)
				)
			)
		)
		(sheetname "/Supply/DC-DC VCCINT/")
		(sheetfile "dc-dc-vccint.kicad_sch")
		(attr smd)
		(fp_rect
			(start -0.925 -0.47)
			(end 0.925 0.47)
			(stroke
				(width 0.05)
				(type default)
			)
			(fill no)
			(layer "F.CrtYd")
		)
		(fp_line
			(start 0.504 -0.25)
			(end 0.504 0.248)
			(stroke
				(width 0.15)
				(type solid)
			)
			(layer "F.Fab")
		)
		(fp_line
			(start -0.494 -0.25)
			(end 0.504 -0.25)
			(stroke
				(width 0.15)
				(type solid)
			)
			(layer "F.Fab")
		)
		(fp_line
			(start 0.504 0.248)
			(end -0.494 0.248)
			(stroke
				(width 0.15)
				(type solid)
			)
			(layer "F.Fab")
		)
		(fp_line
			(start -0.494 0.248)
			(end -0.494 -0.25)
			(stroke
				(width 0.15)
				(type solid)
			)
			(layer "F.Fab")
		)
		(fp_text user "${REFERENCE}"
			(at -0.939 4.599 90)
			(layer "F.Fab")
			(effects
				(font
					(size 0.7 0.7)
					(thickness 0.15)
				)
				(justify left bottom)
			)
		)
		(fp_text user "Author: Antmicro"
			(at -0.939 3.399 90)
			(layer "F.Fab")
			(effects
				(font
					(size 0.7 0.7)
					(thickness 0.15)
				)
				(justify left bottom)
			)
		)
		(fp_text user "License: Apache-2.0"
			(at -0.939 5.799 90)
			(layer "F.Fab")
			(effects
				(font
					(size 0.7 0.7)
					(thickness 0.15)
				)
				(justify left bottom)
			)
		)
		(pad "1" smd roundrect
			(at -0.48 0 90)
			(size 0.59 0.64)
			(layers "F.Cu" "F.Mask" "F.Paste")
			(roundrect_rratio 0.25)
			(net 164 "Net-(U4-BST)")
			(pintype "passive")
		)
		(pad "2" smd roundrect
			(at 0.48 0 90)
			(size 0.59 0.64)
			(layers "F.Cu" "F.Mask" "F.Paste")
			(roundrect_rratio 0.25)
			(net 165 "Net-(C215-Pad2)")
			(pintype "passive")
		)
	)
	(footprint "antmicro-footprints:R_1206_3216Metric"
		(layer "F.Cu")
		(at 256.676 148.148 180)
		(property "Reference" "R147"
			(at 2.176 -0.852 0)
			(layer "F.SilkS")
			(effects
				(font
					(size 0.7 0.7)
					(thickness 0.15)
				)
				(justify right bottom)
			)
		)
		(property "Value" "R_0R01_1206"
			(at 13.377643 2.255091 0)
			(layer "F.Fab")
			(effects
				(font
					(size 0.7 0.7)
					(thickness 0.15)
				)
				(justify right bottom)
			)
		)
		(property "Datasheet" "https://www.yageo.com/upload/media/product/productsearch/datasheet/rchip/PYu-RL_Group_521_RoHS_L_2.pdf"
			(at 0 0 180)
			(layer "F.Fab")
			(hide yes)
			(effects
				(font
					(size 1.27 1.27)
					(thickness 0.15)
				)
			)
		)
		(property "Manufacturer" "YAGEO"
			(at 0 0 180)
			(unlocked yes)
			(layer "F.Fab")
			(hide yes)
			(effects
				(font
					(size 1 1)
					(thickness 0.15)
				)
			)
		)
		(property "MPN" "RL1206FR-7W0R01L"
			(at 0 0 180)
			(unlocked yes)
			(layer "F.Fab")
			(hide yes)
			(effects
				(font
					(size 1 1)
					(thickness 0.15)
				)
			)
		)
		(property "Val" "0R01"
			(at 0 0 180)
			(unlocked yes)
			(layer "F.Fab")
			(hide yes)
			(effects
				(font
					(size 1 1)
					(thickness 0.15)
				)
			)
		)
		(property "License" "Apache-2.0"
			(at 0 0 180)
			(unlocked yes)
			(layer "F.Fab")
			(hide yes)
			(effects
				(font
					(size 1 1)
					(thickness 0.15)
				)
			)
		)
		(property "Author" "Antmicro"
			(at 0 0 180)
			(unlocked yes)
			(layer "F.Fab")
			(hide yes)
			(effects
				(font
					(size 1 1)
					(thickness 0.15)
				)
			)
		)
		(property "Tolerance" "1%"
			(at 0 0 180)
			(unlocked yes)
			(layer "F.Fab")
			(hide yes)
			(effects
				(font
					(size 1 1)
					(thickness 0.15)
				)
			)
		)
		(sheetname "/Supply/DC-DC IO/")
		(sheetfile "dc-dc-io.kicad_sch")
		(attr smd)
		(fp_line
			(start 0.8 0.901)
			(end -0.8 0.901)
			(stroke
				(width 0.15)
				(type solid)
			)
			(layer "F.SilkS")
		)
		(fp_line
			(start 0.8 -0.899)
			(end -0.8 -0.899)
			(stroke
				(width 0.15)
				(type solid)
			)
			(layer "F.SilkS")
		)
		(fp_rect
			(start -2.325 -1.15)
			(end 2.325 1.15)
			(stroke
				(width 0.05)
				(type default)
			)
			(fill no)
			(layer "F.CrtYd")
		)
		(fp_line
			(start 1.6 -0.802)
			(end 1.6 0.8)
			(stroke
				(width 0.15)
				(type solid)
			)
			(layer "F.Fab")
		)
		(fp_line
			(start -1.601 0.8)
			(end 1.6 0.8)
			(stroke
				(width 0.15)
				(type solid)
			)
			(layer "F.Fab")
		)
		(fp_line
			(start -1.601 -0.802)
			(end 1.6 -0.802)
			(stroke
				(width 0.15)
				(type solid)
			)
			(layer "F.Fab")
		)
		(fp_line
			(start -1.601 -0.802)
			(end -1.601 0.8)
			(stroke
				(width 0.15)
				(type solid)
			)
			(layer "F.Fab")
		)
		(fp_text user "${REFERENCE}"
			(at -2.401 3.5 180)
			(layer "F.Fab")
			(effects
				(font
					(size 0.7 0.7)
					(thickness 0.15)
				)
				(justify left bottom)
			)
		)
		(fp_text user "License: Apache-2.0"
			(at -2.401 6.3 180)
			(layer "F.Fab")
			(effects
				(font
					(size 0.7 0.7)
					(thickness 0.15)
				)
				(justify left bottom)
			)
		)
		(fp_text user "Author: Antmicro"
			(at -2.401 4.899 180)
			(layer "F.Fab")
			(effects
				(font
					(size 0.7 0.7)
					(thickness 0.15)
				)
				(justify left bottom)
			)
		)
		(pad "1" smd roundrect
			(at -1.5 0.001 180)
			(size 1.15 1.8)
			(layers "F.Cu" "F.Mask" "F.Paste")
			(roundrect_rratio 0.25)
			(net 158 "/Supply/DC-DC IO/VDDQ_local")
			(pintype "passive")
		)
		(pad "2" smd roundrect
			(at 1.5 0.001 180)
			(size 1.15 1.8)
			(layers "F.Cu" "F.Mask" "F.Paste")
			(roundrect_rratio 0.25)
			(net 687 "VDDQ")
			(pintype "passive")
		)
	)
	(footprint "antmicro-footprints:C_0603_1608Metric"
		(layer "F.Cu")
		(at 215.965 168.76)
		(descr "Capacitor SMD 0603")
		(tags "capacitor 0603")
		(property "Reference" "C266"
			(at -4.144999 0.540001 0)
			(layer "F.SilkS")
			(effects
				(font
					(size 0.7 0.7)
					(thickness 0.15)
				)
				(justify left bottom)
			)
		)
		(property "Value" "C_22u_0603"
			(at -1.42757 1.770288 0)
			(layer "F.Fab")
			(effects
				(font
					(size 0.7 0.7)
					(thickness 0.15)
				)
				(justify left bottom)
			)
		)
		(property "Datasheet" "https://www.murata.com/products/productdetail?partno=GRM188R60J226MEA0%23"
			(at 0 0 0)
			(layer "F.Fab")
			(hide yes)
			(effects
				(font
					(size 1.27 1.27)
					(thickness 0.15)
				)
			)
		)
		(property "Manufacturer" "Murata"
			(at 0 0 0)
			(unlocked yes)
			(layer "F.Fab")
			(hide yes)
			(effects
				(font
					(size 1 1)
					(thickness 0.15)
				)
			)
		)
		(property "MPN" "GRM188R60J226MEA0D"
			(at 0 0 0)
			(unlocked yes)
			(layer "F.Fab")
			(hide yes)
			(effects
				(font
					(size 1 1)
					(thickness 0.15)
				)
			)
		)
		(property "Val" "22u"
			(at 0 0 0)
			(unlocked yes)
			(layer "F.Fab")
			(hide yes)
			(effects
				(font
					(size 1 1)
					(thickness 0.15)
				)
			)
		)
		(property "License" "Apache-2.0"
			(at 0 0 0)
			(unlocked yes)
			(layer "F.Fab")
			(hide yes)
			(effects
				(font
					(size 1 1)
					(thickness 0.15)
				)
			)
		)
		(property "Author" "Antmicro"
			(at 0 0 0)
			(unlocked yes)
			(layer "F.Fab")
			(hide yes)
			(effects
				(font
					(size 1 1)
					(thickness 0.15)
				)
			)
		)
		(property "Voltage" ""
			(at 0 0 0)
			(unlocked yes)
			(layer "F.Fab")
			(hide yes)
			(effects
				(font
					(size 1 1)
					(thickness 0.15)
				)
			)
		)
		(property "Dielectric" ""
			(at 0 0 0)
			(unlocked yes)
			(layer "F.Fab")
			(hide yes)
			(effects
				(font
					(size 1 1)
					(thickness 0.15)
				)
			)
		)
		(sheetname "/Supply/DC-DC VCCINT/")
		(sheetfile "dc-dc-vccint.kicad_sch")
		(attr smd)
		(fp_line
			(start -0.15 -0.4)
			(end 0.15 -0.4)
			(stroke
				(width 0.15)
				(type solid)
			)
			(layer "F.SilkS")
		)
		(fp_line
			(start -0.15 0.4)
			(end 0.15 0.4)
			(stroke
				(width 0.15)
				(type solid)
			)
			(layer "F.SilkS")
		)
		(fp_rect
			(start -1.25 -0.65)
			(end 1.25 0.65)
			(stroke
				(width 0.05)
				(type solid)
			)
			(fill no)
			(layer "F.CrtYd")
		)
		(fp_rect
			(start -0.8 -0.4)
			(end 0.8 0.4)
			(stroke
				(width 0.15)
				(type solid)
			)
			(fill no)
			(layer "F.Fab")
		)
		(fp_text user "Author: Antmicro"
			(at -1.682 4.894 0)
			(layer "F.Fab")
			(effects
				(font
					(size 0.7 0.7)
					(thickness 0.15)
				)
				(justify left bottom)
			)
		)
		(fp_text user "License: Apache-2.0"
			(at -1.682 5.895 0)
			(layer "F.Fab")
			(effects
				(font
					(size 0.7 0.7)
					(thickness 0.15)
				)
				(justify left bottom)
			)
		)
		(fp_text user "${REFERENCE}"
			(at -1.682 3.895 0)
			(layer "F.Fab")
			(effects
				(font
					(size 0.7 0.7)
					(thickness 0.15)
				)
				(justify left bottom)
			)
		)
		(pad "1" smd roundrect
			(at -0.7 0)
			(size 0.8 1)
			(layers "F.Cu" "F.Mask" "F.Paste")
			(roundrect_rratio 0.2)
			(net 1 "GND")
			(pintype "passive")
		)
		(pad "2" smd roundrect
			(at 0.7 0)
			(size 0.8 1)
			(layers "F.Cu" "F.Mask" "F.Paste")
			(roundrect_rratio 0.2)
			(net 223 "/Supply/DC-DC VCCINT/0V85_REG0")
			(pintype "passive")
		)
	)
	(footprint "antmicro-footprints:C_0603_1608Metric"
		(layer "F.Cu")
		(at 250.293 153.921 90)
		(descr "Capacitor SMD 0603")
		(tags "capacitor 0603")
		(property "Reference" "C185"
			(at 1.221 0.507 90)
			(layer "F.SilkS")
			(effects
				(font
					(size 0.7 0.7)
					(thickness 0.15)
				)
				(justify left bottom)
			)
		)
		(property "Value" "C_22u_0603"
			(at -1.42757 1.770288 90)
			(layer "F.Fab")
			(effects
				(font
					(size 0.7 0.7)
					(thickness 0.15)
				)
				(justify left bottom)
			)
		)
		(property "Datasheet" "https://www.murata.com/products/productdetail?partno=GRM188R60J226MEA0%23"
			(at 0 0 90)
			(layer "F.Fab")
			(hide yes)
			(effects
				(font
					(size 1.27 1.27)
					(thickness 0.15)
				)
			)
		)
		(property "Manufacturer" "Murata"
			(at 0 0 90)
			(unlocked yes)
			(layer "F.Fab")
			(hide yes)
			(effects
				(font
					(size 1 1)
					(thickness 0.15)
				)
			)
		)
		(property "MPN" "GRM188R60J226MEA0D"
			(at 0 0 90)
			(unlocked yes)
			(layer "F.Fab")
			(hide yes)
			(effects
				(font
					(size 1 1)
					(thickness 0.15)
				)
			)
		)
		(property "Val" "22u"
			(at 0 0 90)
			(unlocked yes)
			(layer "F.Fab")
			(hide yes)
			(effects
				(font
					(size 1 1)
					(thickness 0.15)
				)
			)
		)
		(property "License" "Apache-2.0"
			(at 0 0 90)
			(unlocked yes)
			(layer "F.Fab")
			(hide yes)
			(effects
				(font
					(size 1 1)
					(thickness 0.15)
				)
			)
		)
		(property "Author" "Antmicro"
			(at 0 0 90)
			(unlocked yes)
			(layer "F.Fab")
			(hide yes)
			(effects
				(font
					(size 1 1)
					(thickness 0.15)
				)
			)
		)
		(property "Voltage" ""
			(at 0 0 90)
			(unlocked yes)
			(layer "F.Fab")
			(hide yes)
			(effects
				(font
					(size 1 1)
					(thickness 0.15)
				)
			)
		)
		(property "Dielectric" ""
			(at 0 0 90)
			(unlocked yes)
			(layer "F.Fab")
			(hide yes)
			(effects
				(font
					(size 1 1)
					(thickness 0.15)
				)
			)
		)
		(sheetname "/Supply/DC-DC IO/")
		(sheetfile "dc-dc-io.kicad_sch")
		(attr smd)
		(fp_line
			(start -0.15 -0.4)
			(end 0.15 -0.4)
			(stroke
				(width 0.15)
				(type solid)
			)
			(layer "F.SilkS")
		)
		(fp_line
			(start -0.15 0.4)
			(end 0.15 0.4)
			(stroke
				(width 0.15)
				(type solid)
			)
			(layer "F.SilkS")
		)
		(fp_rect
			(start -1.25 -0.65)
			(end 1.25 0.65)
			(stroke
				(width 0.05)
				(type solid)
			)
			(fill no)
			(layer "F.CrtYd")
		)
		(fp_rect
			(start -0.8 -0.4)
			(end 0.8 0.4)
			(stroke
				(width 0.15)
				(type solid)
			)
			(fill no)
			(layer "F.Fab")
		)
		(fp_text user "${REFERENCE}"
			(at -1.682 3.895 90)
			(layer "F.Fab")
			(effects
				(font
					(size 0.7 0.7)
					(thickness 0.15)
				)
				(justify left bottom)
			)
		)
		(fp_text user "Author: Antmicro"
			(at -1.682 4.894 90)
			(layer "F.Fab")
			(effects
				(font
					(size 0.7 0.7)
					(thickness 0.15)
				)
				(justify left bottom)
			)
		)
		(fp_text user "License: Apache-2.0"
			(at -1.682 5.895 90)
			(layer "F.Fab")
			(effects
				(font
					(size 0.7 0.7)
					(thickness 0.15)
				)
				(justify left bottom)
			)
		)
		(pad "1" smd roundrect
			(at -0.7 0 90)
			(size 0.8 1)
			(layers "F.Cu" "F.Mask" "F.Paste")
			(roundrect_rratio 0.2)
			(net 1 "GND")
			(pintype "passive")
		)
		(pad "2" smd roundrect
			(at 0.7 0 90)
			(size 0.8 1)
			(layers "F.Cu" "F.Mask" "F.Paste")
			(roundrect_rratio 0.2)
			(net 46 "/Supply/DC-DC IO/5V_local")
			(pintype "passive")
		)
	)
	(footprint "antmicro-footprints:R_0402_1005Metric"
		(layer "F.Cu")
		(at 123.681 168.3125 90)
		(descr "Resistor SMD 0402")
		(tags "resistor SMD 0402")
		(property "Reference" "R220"
			(at -3.825 0.619 90)
			(layer "F.SilkS")
			(effects
				(font
					(size 0.7 0.7)
					(thickness 0.15)
				)
				(justify left bottom)
			)
		)
		(property "Value" "R_64k9_0402"
			(at -1.011843 1.772047 90)
			(layer "F.Fab")
			(effects
				(font
					(size 0.7 0.7)
					(thickness 0.15)
				)
				(justify left bottom)
			)
		)
		(property "Datasheet" "https://www.bourns.com/docs/product-datasheets/cr.pdf"
			(at 0 0 90)
			(layer "F.Fab")
			(hide yes)
			(effects
				(font
					(size 1.27 1.27)
					(thickness 0.15)
				)
			)
		)
		(property "MPN" "CR0402-FX-6492GLF"
			(at 0 0 90)
			(unlocked yes)
			(layer "F.Fab")
			(hide yes)
			(effects
				(font
					(size 1 1)
					(thickness 0.15)
				)
			)
		)
		(property "Manufacturer" "Bourns"
			(at 0 0 90)
			(unlocked yes)
			(layer "F.Fab")
			(hide yes)
			(effects
				(font
					(size 1 1)
					(thickness 0.15)
				)
			)
		)
		(property "License" "Apache-2.0"
			(at 0 0 90)
			(unlocked yes)
			(layer "F.Fab")
			(hide yes)
			(effects
				(font
					(size 1 1)
					(thickness 0.15)
				)
			)
		)
		(property "Author" "Antmicro"
			(at 0 0 90)
			(unlocked yes)
			(layer "F.Fab")
			(hide yes)
			(effects
				(font
					(size 1 1)
					(thickness 0.15)
				)
			)
		)
		(property "Val" "64k9"
			(at 0 0 90)
			(unlocked yes)
			(layer "F.Fab")
			(hide yes)
			(effects
				(font
					(size 1 1)
					(thickness 0.15)
				)
			)
		)
		(property "Tolerance" "1%"
			(at 0 0 90)
			(unlocked yes)
			(layer "F.Fab")
			(hide yes)
			(effects
				(font
					(size 1 1)
					(thickness 0.15)
				)
			)
		)
		(sheetname "/HDMI + SD Card/")
		(sheetfile "hdmi-sd-card.kicad_sch")
		(attr smd exclude_from_bom dnp)
		(fp_rect
			(start -0.925 -0.47)
			(end 0.925 0.47)
			(stroke
				(width 0.05)
				(type default)
			)
			(fill no)
			(layer "F.CrtYd")
		)
		(fp_rect
			(start -0.5 -0.25)
			(end 0.5 0.25)
			(stroke
				(width 0.15)
				(type solid)
			)
			(fill no)
			(layer "F.Fab")
		)
		(fp_text user "Author: Antmicro"
			(at -0.95 4.169 90)
			(layer "F.Fab")
			(effects
				(font
					(size 0.7 0.7)
					(thickness 0.15)
				)
				(justify left bottom)
			)
		)
		(fp_text user "License: Apache-2.0"
			(at -0.95 5.169 90)
			(layer "F.Fab")
			(effects
				(font
					(size 0.7 0.7)
					(thickness 0.15)
				)
				(justify left bottom)
			)
		)
		(fp_text user "${REFERENCE}"
			(at -0.95 3.168 90)
			(layer "F.Fab")
			(effects
				(font
					(size 0.7 0.7)
					(thickness 0.15)
				)
				(justify left bottom)
			)
		)
		(pad "1" smd roundrect
			(at -0.48 0 90)
			(size 0.59 0.64)
			(layers "F.Cu" "F.Mask" "F.Paste")
			(roundrect_rratio 0.25)
			(net 1 "GND")
			(pintype "passive")
		)
		(pad "2" smd roundrect
			(at 0.48 0 90)
			(size 0.59 0.64)
			(layers "F.Cu" "F.Mask" "F.Paste")
			(roundrect_rratio 0.25)
			(net 739 "/HDMI + SD Card/TX_TERM_CTL")
			(pintype "passive")
		)
	)
)
